Altium Designer Pick and Place Locations
C:\Users\<user>\Desktop\WorkNotes\Projects\PTP\Time-Appliance-Project-master\Time-Card\GNSS\UBlox\M2-ZED-F9T\ECAD\Project Outputs for M2_ZED-F9T_MODULE\Pick Place for M2_ZED-F9T_MODULE(845-XXXXX_PCBA_projectname).csv

========================================================================================================================
File Design Information:

Date:       01/07/23
Time:       12:20
Revision:   Not in VersionControl
Variant:    845-XXXXX_PCBA_projectname
Units used: mil

"Designator","Comment","Layer","Footprint","Center-X(mil)","Center-Y(mil)","Rotation","Description"
"D3","LTST-C191KGKT","TopLayer","FP-LTST-C191KGKT-MFG","99.915","461.922","0","LED GREEN CLEAR SMD"
"D2","LTST-C191KGKT","TopLayer","FP-LTST-C191KGKT-MFG","724.409","381.890","0","LED GREEN CLEAR SMD"
"U1","ZED-F9T-00B","TopLayer","GPS_ZED-F9T","435.039","972.835","180","Multi-band GNSS Receiver with Nanosecond-level Timing Accuracy"
"U4","LPV511MGX/NOPB","TopLayer","DCK0005A_N","200.787","1561.929","90","micropower Rail-to-Rail Input and Output Operational Amplifier, 5-pin SC-70, Pb-Free"
"U3","SN74LVC3G07DCUR","TopLayer","DCU0008A_N","82.677","1480.315","270","Triple Buffer/Driver With Open-Drain Output, DCU0008A, LARGE T&R"
"R18","1k","TopLayer","FP-RMCF0402-MFG","43.307","1354.331","270","1kO ±1% 0.063W 0402 Thick Film Chip Resistor AEC-Q200 compliant"
"R17","1k","TopLayer","FP-RMCF0402-MFG","102.362","1354.331","270","1kO ±1% 0.063W 0402 Thick Film Chip Resistor AEC-Q200 compliant"
"P1","U.FL-R-SMT-1(01)","TopLayer","HRS-U.FL-R-SMT-3_V","674.423","1562.989","0","Ultra Small Coaxial Connector, 6 GHz, -40 to 90 degC, 3-Pin SMD, RoHS, Bulk"
"D1","PESD0402-140","TopLayer","FP-PESD0402-MFG","698.995","1478.892","180","TVS DIODE 14V 40V 0402"
"C12","10nF","TopLayer","FP-GRM033-0_03-IPC_B","598.274","1421.324","270","Chip Multilayer Ceramic Capacitors for General Purpose, 0201, 10000pF, X7R, 15%, 10%, 16V"
"C11","100nF","TopLayer","FP-0402-L_1_0_0_05-W_0_5-IPC_B","157.480","1377.953","270","None"
"C10","100nF","TopLayer","FP-0402-L_1_0_0_05-W_0_5-IPC_B","673.228","1374.016","90","None"
"C9","100nF","TopLayer","FP-0402-L_1_0_0_05-W_0_5-IPC_B","106.299","1614.173","180","None"
"R16","22_1%_1218 1.5W","TopLayer","FP-CRCW1218-HPe3-MFG","472.441","1425.197","270","RES Thick Film, 22.6O, 1%, 1.5W, 100ppm/°C, 1218"
"R15","0_5%_0402","TopLayer","RESC1005X40X25NL05T10","409.449","307.087","90",""
"R14","DNI_0_5%_0402","TopLayer","RESC1005X40X25NL05T10","448.819","307.087","90",""
"R13","0_5%_0402","TopLayer","RESC1005X40X25NL05T10","318.898","318.898","270",""
"R12","0_5%_0402","TopLayer","RESC1005X40X25NL05T10","271.654","318.898","270",""
"R11","100k","TopLayer","FP-RMCF0402-IPC_C","248.031","1469.441","0","100kO ±1% 0.063W 0402 Thick Film Chip Resistor AEC-Q200 compliant"
"R2","0_5%_0402","TopLayer","RESC1005X40X25NL05T10","311.024","440.945","180",""
"C7","47uF_6.3V_1206","TopLayer","FP-GRM31C-0_2-e0_3_0_8-IPC_C","98.425","267.716","180","Chip Multilayer Ceramic Capacitors for General Purpose, 1206, 47uF, X5R, 15%, 20%, 6.3V"
"C6","47uF_6.3V_1206","TopLayer","FP-GRM31C-0_2-e0_3_0_8-IPC_C","795.276","251.969","90","Chip Multilayer Ceramic Capacitors for General Purpose, 1206, 47uF, X5R, 15%, 20%, 6.3V"
"R9","100k","TopLayer","FP-RMCF0402-IPC_C","212.598","1401.575","270","100kO ±1% 0.063W 0402 Thick Film Chip Resistor AEC-Q200 compliant"
"R7","1k","TopLayer","FP-RMCF0402-MFG","106.299","515.748","180","1kO ±1% 0.063W 0402 Thick Film Chip Resistor AEC-Q200 compliant"
"Q1","NTR2101PT1G","TopLayer","ONSC-SOT-23-3-318-08_V","299.213","1385.827","0","Small Signal MOSFET, -8 V, -3.7 A, Single P-Channel, 3-Pin SOT-23, Pb-Free, Tape and Reel"
"C5","1uF_25V_0402","TopLayer","FP-CL542-IPC_C","251.969","500.000","0","Cap Ceramic 1uF 25V X5R ±10% SMD 0402 +85°C Paper T/R"
"R10","1k","TopLayer","FP-RMCF0402-MFG","322.835","1469.488","0","1kO ±1% 0.063W 0402 Thick Film Chip Resistor AEC-Q200 compliant"
"R4","1k","TopLayer","FP-RMCF0402-MFG","629.921","381.890","0","1kO ±1% 0.063W 0402 Thick Film Chip Resistor AEC-Q200 compliant"
"R3","0_5%_0402","TopLayer","RESC1005X40X25NL05T10","311.024","397.638","180",""
"R1","1k","TopLayer","FP-RMCF0402-MFG","251.969","551.181","180","1kO ±1% 0.063W 0402 Thick Film Chip Resistor AEC-Q200 compliant"
"L1","47nH 300mA","TopLayer","FP-LQG15HH_02-IPC_B","657.001","1436.139","0","Multilayer type RF Inductor 47nH ±5% 0.72O 300mA 0402"
"J1","OCPTAP_M2_FINGERS","TopLayer","OCPTAP_M2_FINGERS","433.071","55.118","0",""
"C4","1uF_25V_0402","TopLayer","FP-CL542-IPC_C","519.685","570.866","0","Cap Ceramic 1uF 25V X5R ±10% SMD 0402 +85°C Paper T/R"
"C3","1uF_25V_0402","TopLayer","FP-CL542-IPC_C","519.685","610.236","0","Cap Ceramic 1uF 25V X5R ±10% SMD 0402 +85°C Paper T/R"
"C2","1uF_25V_0402","TopLayer","FP-CL542-IPC_C","433.071","610.236","0","Cap Ceramic 1uF 25V X5R ±10% SMD 0402 +85°C Paper T/R"
"C1","1uF_25V_0402","TopLayer","FP-CL542-IPC_C","346.546","611.126","180","Cap Ceramic 1uF 25V X5R ±10% SMD 0402 +85°C Paper T/R"
